(kicad_pcb
	(version 20260206)
	(generator "pcbnew")
	(generator_version "10.0")
	(general
		(thickness 1.6)
		(legacy_teardrops no)
	)
	(paper "A4")
	(title_block
		(title "Bryce Canyon_F.DPB_16315-1-OCP.brd")
		(comment 1 "Bryce Canyon / footprints 1053-1059 of 2223")
	)
	(layers
		(0 "F.Cu" signal "TOP")
		(4 "In1.Cu" signal "L2GND")
		(6 "In2.Cu" signal "L3")
		(8 "In3.Cu" signal "L4GND")
		(10 "In4.Cu" signal "L5")
		(12 "In5.Cu" signal "L6VCC")
		(14 "In6.Cu" signal "L7VCC")
		(16 "In7.Cu" signal "L8")
		(18 "In8.Cu" signal "L9GND")
		(20 "In9.Cu" signal "L10")
		(22 "In10.Cu" signal "L11GND")
		(2 "B.Cu" signal "BOTTOM")
		(9 "F.Adhes" user "F.Adhesive")
		(11 "B.Adhes" user "B.Adhesive")
		(13 "F.Paste" user "Package Geometry/Pastemask Top")
		(15 "B.Paste" user "Package Geometry/Pastemask Bottom")
		(5 "F.SilkS" user "Ref Des/Silkscreen Top")
		(7 "B.SilkS" user "Ref Des/Silkscreen Bottom")
		(1 "F.Mask" user "Board Geometry/Soldermask Top")
		(3 "B.Mask" user "Board Geometry/Soldermask Bottom")
		(17 "Dwgs.User" user "User.Drawings")
		(19 "Cmts.User" user "User.Comments")
		(21 "Eco1.User" user "User.Eco1")
		(23 "Eco2.User" user "User.Eco2")
		(25 "Edge.Cuts" user "Board Geometry/Outline")
		(27 "Margin" user)
		(31 "F.CrtYd" user "Package Geometry/Place Bound Top")
		(29 "B.CrtYd" user "Package Geometry/Place Bound Bottom")
		(35 "F.Fab" user "Ref Des/Assembly Top")
		(33 "B.Fab" user "Ref Des/Assembly Bottom")
	)
	(footprint ""
		(layer "F.Cu")
		(at 67.347846 -176.127918 90)
		(property "Reference" "C215"
			(at 0 0 90)
			(layer "F.SilkS")
			(hide yes)
			(effects
				(font
					(size 1.27 1.27)
				)
			)
		)
		(property "Value" "SCD01U50V2KX-1GP"
			(at 1.1811 -2.7051 90)
			(unlocked yes)
			(layer "F.Fab")
			(hide yes)
			(effects
				(font
					(size 1.016 1.016)
					(thickness 0.1524)
				)
			)
		)
		(property "Device Type" "C402H22"
			(at 1.1811 -4.2291 90)
			(unlocked yes)
			(layer "F.Fab")
			(hide yes)
			(effects
				(font
					(size 1.016 1.016)
					(thickness 0.1524)
				)
			)
		)
		(duplicate_pad_numbers_are_jumpers no)
		(fp_rect
			(start -0.4318 0.9525)
			(end 0.4318 -0.9525)
			(stroke
				(width 0)
				(type default)
			)
			(fill no)
			(layer "F.CrtYd")
		)
		(fp_rect
			(start -0.4318 0.9525)
			(end 0.4318 -0.9525)
			(stroke
				(width 0)
				(type default)
			)
			(fill no)
			(layer "F.Fab")
		)
		(pad "1" smd custom
			(at 0 -0.4445 90)
			(size 0.1524 0.1524)
			(layers "F.Cu" "F.Mask" "F.Paste")
			(net "HDD_PRSNT_13")
			(options
				(clearance outline)
				(anchor circle)
			)
			(primitives
				(gr_poly
					(pts
						(arc
							(start 0.3048 -0.2032)
							(mid 0.275042 -0.275042)
							(end 0.2032 -0.3048)
						)
						(arc
							(start -0.2032 -0.3048)
							(mid -0.275042 -0.275042)
							(end -0.3048 -0.2032)
						)
						(arc
							(start -0.3048 0.2032)
							(mid -0.275042 0.275042)
							(end -0.2032 0.3048)
						)
						(arc
							(start 0.2032 0.3048)
							(mid 0.275042 0.275042)
							(end 0.3048 0.2032)
						)
					)
					(width 0)
					(fill yes)
				)
			)
		)
		(pad "2" smd custom
			(at 0 0.4445 90)
			(size 0.1524 0.1524)
			(layers "F.Cu" "F.Mask" "F.Paste")
			(net "GND")
			(options
				(clearance outline)
				(anchor circle)
			)
			(primitives
				(gr_poly
					(pts
						(arc
							(start 0.3048 -0.2032)
							(mid 0.275042 -0.275042)
							(end 0.2032 -0.3048)
						)
						(arc
							(start -0.2032 -0.3048)
							(mid -0.275042 -0.275042)
							(end -0.3048 -0.2032)
						)
						(arc
							(start -0.3048 0.2032)
							(mid -0.275042 0.275042)
							(end -0.2032 0.3048)
						)
						(arc
							(start 0.2032 0.3048)
							(mid 0.275042 0.275042)
							(end 0.3048 0.2032)
						)
					)
					(width 0)
					(fill yes)
				)
			)
		)
	)
	(footprint ""
		(layer "F.Cu")
		(at 335.228438 -33.550352 180)
		(property "Reference" "R100"
			(at 0 0 180)
			(layer "F.SilkS")
			(hide yes)
			(effects
				(font
					(size 1.27 1.27)
				)
			)
		)
		(property "Value" "0R2J-2-GP"
			(at 0.064008 -3.993896 180)
			(unlocked yes)
			(layer "F.Fab")
			(hide yes)
			(effects
				(font
					(size 1.016 1.016)
					(thickness 0.1524)
				)
			)
		)
		(property "Device Type" "R402H16"
			(at 0.064008 -5.517896 180)
			(unlocked yes)
			(layer "F.Fab")
			(hide yes)
			(effects
				(font
					(size 1.016 1.016)
					(thickness 0.1524)
				)
			)
		)
		(duplicate_pad_numbers_are_jumpers no)
		(fp_line
			(start 0.508 -0.9398)
			(end -0.508 -0.9398)
			(stroke
				(width 0.1524)
				(type default)
			)
			(layer "F.SilkS")
		)
		(fp_line
			(start -0.508 -0.9398)
			(end -0.508 0.9398)
			(stroke
				(width 0.1524)
				(type default)
			)
			(layer "F.SilkS")
		)
		(fp_rect
			(start -0.508 0.9398)
			(end 0.508 -0.9398)
			(stroke
				(width 0)
				(type default)
			)
			(fill no)
			(layer "F.CrtYd")
		)
		(fp_rect
			(start -0.508 0.9398)
			(end 0.508 -0.9398)
			(stroke
				(width 0)
				(type default)
			)
			(fill no)
			(layer "F.Fab")
		)
		(pad "1" smd custom
			(at 0 -0.4445 180)
			(size 0.1397 0.1397)
			(layers "F.Cu" "F.Mask" "F.Paste")
			(net "IO_EXP11_SDA")
			(options
				(clearance outline)
				(anchor circle)
			)
			(primitives
				(gr_poly
					(pts
						(arc
							(start -0.1778 -0.2794)
							(mid -0.249642 -0.249642)
							(end -0.2794 -0.1778)
						)
						(arc
							(start -0.2794 0.1778)
							(mid -0.249642 0.249642)
							(end -0.1778 0.2794)
						)
						(arc
							(start 0.1778 0.2794)
							(mid 0.249642 0.249642)
							(end 0.2794 0.1778)
						)
						(arc
							(start 0.2794 -0.1778)
							(mid 0.249642 -0.249642)
							(end 0.1778 -0.2794)
						)
					)
					(width 0)
					(fill yes)
				)
			)
		)
		(pad "2" smd custom
			(at 0 0.4445 180)
			(size 0.1397 0.1397)
			(layers "F.Cu" "F.Mask" "F.Paste")
			(net "I2C_BMC_B_MISC_SDA")
			(options
				(clearance outline)
				(anchor circle)
			)
			(primitives
				(gr_poly
					(pts
						(arc
							(start -0.1778 -0.2794)
							(mid -0.249642 -0.249642)
							(end -0.2794 -0.1778)
						)
						(arc
							(start -0.2794 0.1778)
							(mid -0.249642 0.249642)
							(end -0.1778 0.2794)
						)
						(arc
							(start 0.1778 0.2794)
							(mid 0.249642 0.249642)
							(end 0.2794 0.1778)
						)
						(arc
							(start 0.2794 -0.1778)
							(mid 0.249642 -0.249642)
							(end 0.1778 -0.2794)
						)
					)
					(width 0)
					(fill yes)
				)
			)
		)
	)
	(footprint ""
		(layer "F.Cu")
		(at 146.249898 -61.000894 -90)
		(property "Reference" "C405"
			(at 0 0 270)
			(layer "F.SilkS")
			(hide yes)
			(effects
				(font
					(size 1.27 1.27)
				)
			)
		)
		(property "Value" "SC10U16V6KX-2GP"
			(at -0.0762 -5.1308 270)
			(unlocked yes)
			(layer "F.Fab")
			(hide yes)
			(effects
				(font
					(size 1.016 1.016)
					(thickness 0.1524)
				)
			)
		)
		(property "Device Type" "C1206H71"
			(at -0.127 -6.6548 270)
			(unlocked yes)
			(layer "F.Fab")
			(hide yes)
			(effects
				(font
					(size 1.016 1.016)
					(thickness 0.1524)
				)
			)
		)
		(duplicate_pad_numbers_are_jumpers no)
		(fp_line
			(start -1.016 2.2352)
			(end -1.016 0.8382)
			(stroke
				(width 0.1524)
				(type default)
			)
			(layer "F.SilkS")
		)
		(fp_line
			(start 1.016 2.2352)
			(end -1.016 2.2352)
			(stroke
				(width 0.1524)
				(type default)
			)
			(layer "F.SilkS")
		)
		(fp_line
			(start 1.016 0.8382)
			(end 1.016 2.2352)
			(stroke
				(width 0.1524)
				(type default)
			)
			(layer "F.SilkS")
		)
		(fp_line
			(start -1.016 -0.8382)
			(end -1.016 -2.2352)
			(stroke
				(width 0.1524)
				(type default)
			)
			(layer "F.SilkS")
		)
		(fp_line
			(start -1.016 -2.2352)
			(end 1.016 -2.2352)
			(stroke
				(width 0.1524)
				(type default)
			)
			(layer "F.SilkS")
		)
		(fp_line
			(start 1.016 -2.2352)
			(end 1.016 -0.8382)
			(stroke
				(width 0.1524)
				(type default)
			)
			(layer "F.SilkS")
		)
		(fp_rect
			(start -1.0922 2.3114)
			(end 1.0922 -2.3114)
			(stroke
				(width 0)
				(type default)
			)
			(fill no)
			(layer "F.CrtYd")
		)
		(fp_poly
			(pts
				(xy 1.0922 -2.3114) (xy 1.0922 2.3114) (xy -1.0922 2.3114) (xy -1.0922 -2.3114)
			)
			(stroke
				(width 0)
				(type default)
			)
			(fill no)
			(layer "F.Fab")
		)
		(pad "1" smd rect
			(at 0 -1.397 270)
			(size 1.651 1.27)
			(layers "F.Cu" "F.Mask" "F.Paste")
			(net "P5V_HDD28")
		)
		(pad "2" smd rect
			(at 0 1.397 270)
			(size 1.651 1.27)
			(layers "F.Cu" "F.Mask" "F.Paste")
			(net "GND")
		)
	)
	(footprint ""
		(layer "F.Cu")
		(at 83.530948 -177.778918 -90)
		(property "Reference" "C222"
			(at 0 0 270)
			(layer "F.SilkS")
			(hide yes)
			(effects
				(font
					(size 1.27 1.27)
				)
			)
		)
		(property "Value" "SC1U16V3KX-5GP"
			(at 0 -2.8194 270)
			(unlocked yes)
			(layer "F.Fab")
			(hide yes)
			(effects
				(font
					(size 1.016 1.016)
					(thickness 0.1524)
				)
			)
		)
		(property "Device Type" "C603H36"
			(at 0 -4.3434 270)
			(unlocked yes)
			(layer "F.Fab")
			(hide yes)
			(effects
				(font
					(size 1.016 1.016)
					(thickness 0.1524)
				)
			)
		)
		(duplicate_pad_numbers_are_jumpers no)
		(fp_line
			(start 0.508 0)
			(end -0.508 0)
			(stroke
				(width 0.2032)
				(type default)
			)
			(layer "F.SilkS")
		)
		(fp_rect
			(start -0.5842 1.3335)
			(end 0.5842 -1.3335)
			(stroke
				(width 0)
				(type default)
			)
			(fill no)
			(layer "F.CrtYd")
		)
		(fp_rect
			(start -0.5842 1.3335)
			(end 0.5842 -1.3335)
			(stroke
				(width 0)
				(type default)
			)
			(fill no)
			(layer "F.Fab")
		)
		(pad "1" smd custom
			(at 0 -0.762 270)
			(size 0.2159 0.2159)
			(layers "F.Cu" "F.Mask" "F.Paste")
			(net "P5V_HDD14")
			(options
				(clearance outline)
				(anchor circle)
			)
			(primitives
				(gr_poly
					(pts
						(arc
							(start -0.3302 -0.4318)
							(mid -0.402042 -0.402042)
							(end -0.4318 -0.3302)
						)
						(arc
							(start -0.4318 0.3302)
							(mid -0.402042 0.402042)
							(end -0.3302 0.4318)
						)
						(arc
							(start 0.3302 0.4318)
							(mid 0.402042 0.402042)
							(end 0.4318 0.3302)
						)
						(arc
							(start 0.4318 -0.3302)
							(mid 0.402042 -0.402042)
							(end 0.3302 -0.4318)
						)
					)
					(width 0)
					(fill yes)
				)
			)
		)
		(pad "2" smd custom
			(at 0 0.762 270)
			(size 0.2159 0.2159)
			(layers "F.Cu" "F.Mask" "F.Paste")
			(net "GND")
			(options
				(clearance outline)
				(anchor circle)
			)
			(primitives
				(gr_poly
					(pts
						(arc
							(start -0.3302 -0.4318)
							(mid -0.402042 -0.402042)
							(end -0.4318 -0.3302)
						)
						(arc
							(start -0.4318 0.3302)
							(mid -0.402042 0.402042)
							(end -0.3302 0.4318)
						)
						(arc
							(start 0.3302 0.4318)
							(mid 0.402042 0.402042)
							(end 0.4318 0.3302)
						)
						(arc
							(start 0.4318 -0.3302)
							(mid 0.402042 -0.402042)
							(end 0.3302 -0.4318)
						)
					)
					(width 0)
					(fill yes)
				)
			)
		)
	)
	(footprint ""
		(layer "F.Cu")
		(at 236.871256 -343.309448)
		(property "Reference" "R185"
			(at 0 0 0)
			(layer "F.SilkS")
			(hide yes)
			(effects
				(font
					(size 1.27 1.27)
				)
			)
		)
		(property "Value" "10KR2F-2-GP"
			(at 0.064008 -3.993896 0)
			(unlocked yes)
			(layer "F.Fab")
			(hide yes)
			(effects
				(font
					(size 1.016 1.016)
					(thickness 0.1524)
				)
			)
		)
		(property "Device Type" "R402H16"
			(at 0.064008 -5.517896 0)
			(unlocked yes)
			(layer "F.Fab")
			(hide yes)
			(effects
				(font
					(size 1.016 1.016)
					(thickness 0.1524)
				)
			)
		)
		(duplicate_pad_numbers_are_jumpers no)
		(fp_line
			(start -0.508 -0.9398)
			(end -0.508 0.9398)
			(stroke
				(width 0.1524)
				(type default)
			)
			(layer "F.SilkS")
		)
		(fp_line
			(start 0.508 -0.9398)
			(end -0.508 -0.9398)
			(stroke
				(width 0.1524)
				(type default)
			)
			(layer "F.SilkS")
		)
		(fp_rect
			(start -0.508 0.9398)
			(end 0.508 -0.9398)
			(stroke
				(width 0)
				(type default)
			)
			(fill no)
			(layer "F.CrtYd")
		)
		(fp_rect
			(start -0.508 0.9398)
			(end 0.508 -0.9398)
			(stroke
				(width 0)
				(type default)
			)
			(fill no)
			(layer "F.Fab")
		)
		(pad "1" smd custom
			(at 0 -0.4445)
			(size 0.1397 0.1397)
			(layers "F.Cu" "F.Mask" "F.Paste")
			(net "P5V_A_4_SENSE")
			(options
				(clearance outline)
				(anchor circle)
			)
			(primitives
				(gr_poly
					(pts
						(arc
							(start -0.1778 -0.2794)
							(mid -0.249642 -0.249642)
							(end -0.2794 -0.1778)
						)
						(arc
							(start -0.2794 0.1778)
							(mid -0.249642 0.249642)
							(end -0.1778 0.2794)
						)
						(arc
							(start 0.1778 0.2794)
							(mid 0.249642 0.249642)
							(end 0.2794 0.1778)
						)
						(arc
							(start 0.2794 -0.1778)
							(mid 0.249642 -0.249642)
							(end 0.1778 -0.2794)
						)
					)
					(width 0)
					(fill yes)
				)
			)
		)
		(pad "2" smd custom
			(at 0 0.4445)
			(size 0.1397 0.1397)
			(layers "F.Cu" "F.Mask" "F.Paste")
			(net "GND")
			(options
				(clearance outline)
				(anchor circle)
			)
			(primitives
				(gr_poly
					(pts
						(arc
							(start -0.1778 -0.2794)
							(mid -0.249642 -0.249642)
							(end -0.2794 -0.1778)
						)
						(arc
							(start -0.2794 0.1778)
							(mid -0.249642 0.249642)
							(end -0.1778 0.2794)
						)
						(arc
							(start 0.1778 0.2794)
							(mid 0.249642 0.249642)
							(end 0.2794 0.1778)
						)
						(arc
							(start 0.2794 -0.1778)
							(mid 0.249642 -0.249642)
							(end 0.1778 -0.2794)
						)
					)
					(width 0)
					(fill yes)
				)
			)
		)
	)
	(footprint ""
		(layer "F.Cu")
		(at 475.529148 -269.348204 180)
		(property "Reference" "R394"
			(at 0 0 180)
			(layer "F.SilkS")
			(hide yes)
			(effects
				(font
					(size 1.27 1.27)
				)
			)
		)
		(property "Value" "0R2J-2-GP"
			(at 0.064008 -3.993896 180)
			(unlocked yes)
			(layer "F.Fab")
			(hide yes)
			(effects
				(font
					(size 1.016 1.016)
					(thickness 0.1524)
				)
			)
		)
		(property "Device Type" "R402H16"
			(at 0.064008 -5.517896 180)
			(unlocked yes)
			(layer "F.Fab")
			(hide yes)
			(effects
				(font
					(size 1.016 1.016)
					(thickness 0.1524)
				)
			)
		)
		(duplicate_pad_numbers_are_jumpers no)
		(fp_line
			(start 0.508 -0.9398)
			(end -0.508 -0.9398)
			(stroke
				(width 0.1524)
				(type default)
			)
			(layer "F.SilkS")
		)
		(fp_line
			(start -0.508 -0.9398)
			(end -0.508 0.9398)
			(stroke
				(width 0.1524)
				(type default)
			)
			(layer "F.SilkS")
		)
		(fp_rect
			(start -0.508 0.9398)
			(end 0.508 -0.9398)
			(stroke
				(width 0)
				(type default)
			)
			(fill no)
			(layer "F.CrtYd")
		)
		(fp_rect
			(start -0.508 0.9398)
			(end 0.508 -0.9398)
			(stroke
				(width 0)
				(type default)
			)
			(fill no)
			(layer "F.Fab")
		)
		(pad "1" smd custom
			(at 0 -0.4445 180)
			(size 0.1397 0.1397)
			(layers "F.Cu" "F.Mask" "F.Paste")
			(net "DRIVE_A_11_PWR")
			(options
				(clearance outline)
				(anchor circle)
			)
			(primitives
				(gr_poly
					(pts
						(arc
							(start -0.1778 -0.2794)
							(mid -0.249642 -0.249642)
							(end -0.2794 -0.1778)
						)
						(arc
							(start -0.2794 0.1778)
							(mid -0.249642 0.249642)
							(end -0.1778 0.2794)
						)
						(arc
							(start 0.1778 0.2794)
							(mid 0.249642 0.249642)
							(end 0.2794 0.1778)
						)
						(arc
							(start 0.2794 -0.1778)
							(mid 0.249642 -0.249642)
							(end 0.1778 -0.2794)
						)
					)
					(width 0)
					(fill yes)
				)
			)
		)
		(pad "2" smd custom
			(at 0 0.4445 180)
			(size 0.1397 0.1397)
			(layers "F.Cu" "F.Mask" "F.Paste")
			(net "SW_PWR_R_HDD11")
			(options
				(clearance outline)
				(anchor circle)
			)
			(primitives
				(gr_poly
					(pts
						(arc
							(start -0.1778 -0.2794)
							(mid -0.249642 -0.249642)
							(end -0.2794 -0.1778)
						)
						(arc
							(start -0.2794 0.1778)
							(mid -0.249642 0.249642)
							(end -0.1778 0.2794)
						)
						(arc
							(start 0.1778 0.2794)
							(mid 0.249642 0.249642)
							(end 0.2794 0.1778)
						)
						(arc
							(start 0.2794 -0.1778)
							(mid 0.249642 -0.249642)
							(end 0.1778 -0.2794)
						)
					)
					(width 0)
					(fill yes)
				)
			)
		)
	)
	(footprint ""
		(layer "F.Cu")
		(at 475.246192 -286.120332 -90)
		(property "Reference" "C184"
			(at 0 0 270)
			(layer "F.SilkS")
			(hide yes)
			(effects
				(font
					(size 1.27 1.27)
				)
			)
		)
		(property "Value" "SC10U16V6KX-2GP"
			(at -0.0762 -5.1308 270)
			(unlocked yes)
			(layer "F.Fab")
			(hide yes)
			(effects
				(font
					(size 1.016 1.016)
					(thickness 0.1524)
				)
			)
		)
		(property "Device Type" "C1206H71"
			(at -0.127 -6.6548 270)
			(unlocked yes)
			(layer "F.Fab")
			(hide yes)
			(effects
				(font
					(size 1.016 1.016)
					(thickness 0.1524)
				)
			)
		)
		(duplicate_pad_numbers_are_jumpers no)
		(fp_line
			(start -1.016 2.2352)
			(end -1.016 0.8382)
			(stroke
				(width 0.1524)
				(type default)
			)
			(layer "F.SilkS")
		)
		(fp_line
			(start 1.016 2.2352)
			(end -1.016 2.2352)
			(stroke
				(width 0.1524)
				(type default)
			)
			(layer "F.SilkS")
		)
		(fp_line
			(start 1.016 0.8382)
			(end 1.016 2.2352)
			(stroke
				(width 0.1524)
				(type default)
			)
			(layer "F.SilkS")
		)
		(fp_line
			(start -1.016 -0.8382)
			(end -1.016 -2.2352)
			(stroke
				(width 0.1524)
				(type default)
			)
			(layer "F.SilkS")
		)
		(fp_line
			(start -1.016 -2.2352)
			(end 1.016 -2.2352)
			(stroke
				(width 0.1524)
				(type default)
			)
			(layer "F.SilkS")
		)
		(fp_line
			(start 1.016 -2.2352)
			(end 1.016 -0.8382)
			(stroke
				(width 0.1524)
				(type default)
			)
			(layer "F.SilkS")
		)
		(fp_rect
			(start -1.0922 2.3114)
			(end 1.0922 -2.3114)
			(stroke
				(width 0)
				(type default)
			)
			(fill no)
			(layer "F.CrtYd")
		)
		(fp_poly
			(pts
				(xy 1.0922 -2.3114) (xy 1.0922 2.3114) (xy -1.0922 2.3114) (xy -1.0922 -2.3114)
			)
			(stroke
				(width 0)
				(type default)
			)
			(fill no)
			(layer "F.Fab")
		)
		(pad "1" smd rect
			(at 0 -1.397 270)
			(size 1.651 1.27)
			(layers "F.Cu" "F.Mask" "F.Paste")
			(net "P5V_HDD11")
		)
		(pad "2" smd rect
			(at 0 1.397 270)
			(size 1.651 1.27)
			(layers "F.Cu" "F.Mask" "F.Paste")
			(net "GND")
		)
	)
)
